# BASEBOARD_FAB2 (Tioga Pass) — schematic netlist excerpt (pin names and nets, part order shuffled) for the footprints in the layout excerpt that follows; sources: Cadence DE-HDL packaged netlist, KiCad conversion of Wiwynn_Tioga_Pass_MB.brd

C4A13  CAP  22UF 4V 20% X6S  pkg 0805LF  page 230 : A = PVTT_KLM ; B = GND
RT34  1R3F-GP  1%  pkg RCL_GP  page 216 : \1\ = VR_PVDDQ_ABC_PH1_SW_RC ; \2\ = GND
C1F5  CAP  0.22UF 16V 10% X7R  pkg 0402  page 181 : A = P3E_CPU1_PE3_MP_C_TXP<6> ; B = P3E_CPU1_PE3_MP_TXP<6>

(kicad_pcb
	(version 20260206)
	(generator "pcbnew")
	(generator_version "10.0")
	(general
		(thickness 1.6)
		(legacy_teardrops no)
	)
	(paper "A4")
	(title_block
		(title "Wiwynn_Tioga_Pass_MB.brd")
		(comment 1 "Tioga Pass / footprints 1510-1512 of 4770")
	)
	(layers
		(0 "F.Cu" signal "TOP")
		(4 "In1.Cu" signal "L2GND")
		(6 "In2.Cu" signal "L3")
		(8 "In3.Cu" signal "L4GND")
		(10 "In4.Cu" signal "L5")
		(12 "In5.Cu" signal "L6GND")
		(14 "In6.Cu" signal "L7VCC")
		(16 "In7.Cu" signal "L8VCC")
		(18 "In8.Cu" signal "L9GND")
		(20 "In9.Cu" signal "L10")
		(22 "In10.Cu" signal "L11GND")
		(24 "In11.Cu" signal "L12")
		(26 "In12.Cu" signal "L13GND")
		(2 "B.Cu" signal "BOTTOM")
		(9 "F.Adhes" user "F.Adhesive")
		(11 "B.Adhes" user "B.Adhesive")
		(13 "F.Paste" user "Package Geometry/Pastemask Top")
		(15 "B.Paste" user "Package Geometry/Pastemask Bottom")
		(5 "F.SilkS" user "Ref Des/Silkscreen Top")
		(7 "B.SilkS" user "Ref Des/Silkscreen Bottom")
		(1 "F.Mask" user "Board Geometry/Soldermask Top")
		(3 "B.Mask" user "Board Geometry/Soldermask Bottom")
		(17 "Dwgs.User" user "User.Drawings")
		(19 "Cmts.User" user "User.Comments")
		(21 "Eco1.User" user "User.Eco1")
		(23 "Eco2.User" user "User.Eco2")
		(25 "Edge.Cuts" user "Board Geometry/Outline")
		(27 "Margin" user)
		(31 "F.CrtYd" user "Package Geometry/Place Bound Top")
		(29 "B.CrtYd" user "Package Geometry/Place Bound Bottom")
		(35 "F.Fab" user "Ref Des/Assembly Top")
		(33 "B.Fab" user "Ref Des/Assembly Bottom")
	)
	(footprint ""
		(layer "F.Cu")
		(at 340.429088 -10.34161 90)
		(property "Reference" "RT34"
			(at 0 0 90)
			(layer "F.SilkS")
			(hide yes)
			(effects
				(font
					(size 1.27 1.27)
				)
			)
		)
		(property "Value" "*"
			(at -0.0254 -2.6289 90)
			(unlocked yes)
			(layer "F.Fab")
			(hide yes)
			(effects
				(font
					(size 1.27 1.016)
					(thickness 0.1524)
				)
			)
		)
		(property "Device Type" "1R3F-GP_RCL_GP-1R3F-GP,64.1R00A"
			(at -0.0254 -4.1529 90)
			(unlocked yes)
			(layer "F.Fab")
			(hide yes)
			(effects
				(font
					(size 1.27 1.016)
					(thickness 0.1524)
				)
			)
		)
		(duplicate_pad_numbers_are_jumpers no)
		(fp_line
			(start 0.2032 0)
			(end 0.4826 0)
			(stroke
				(width 0.2032)
				(type default)
			)
			(layer "F.SilkS")
		)
		(fp_line
			(start -0.4826 0)
			(end -0.2032 0)
			(stroke
				(width 0.2032)
				(type default)
			)
			(layer "F.SilkS")
		)
		(fp_rect
			(start -0.5842 1.3335)
			(end 0.5842 -1.3335)
			(stroke
				(width 0)
				(type default)
			)
			(fill no)
			(layer "F.CrtYd")
		)
		(fp_rect
			(start -0.5842 1.3335)
			(end 0.5842 -1.3335)
			(stroke
				(width 0)
				(type default)
			)
			(fill no)
			(layer "F.Fab")
		)
		(pad "1" smd custom
			(at 0 -0.762 90)
			(size 0.2159 0.2159)
			(layers "F.Cu" "F.Mask" "F.Paste")
			(net "VR_PVDDQ_ABC_PH1_SW_RC")
			(options
				(clearance outline)
				(anchor circle)
			)
			(primitives
				(gr_poly
					(pts
						(arc
							(start -0.3302 -0.4318)
							(mid -0.402042 -0.402042)
							(end -0.4318 -0.3302)
						)
						(arc
							(start -0.4318 0.3302)
							(mid -0.402042 0.402042)
							(end -0.3302 0.4318)
						)
						(arc
							(start 0.3302 0.4318)
							(mid 0.402042 0.402042)
							(end 0.4318 0.3302)
						)
						(arc
							(start 0.4318 -0.3302)
							(mid 0.402042 -0.402042)
							(end 0.3302 -0.4318)
						)
					)
					(width 0)
					(fill yes)
				)
			)
		)
		(pad "2" smd custom
			(at 0 0.762 90)
			(size 0.2159 0.2159)
			(layers "F.Cu" "F.Mask" "F.Paste")
			(net "GND")
			(options
				(clearance outline)
				(anchor circle)
			)
			(primitives
				(gr_poly
					(pts
						(arc
							(start -0.3302 -0.4318)
							(mid -0.402042 -0.402042)
							(end -0.4318 -0.3302)
						)
						(arc
							(start -0.4318 0.3302)
							(mid -0.402042 0.402042)
							(end -0.3302 0.4318)
						)
						(arc
							(start 0.3302 0.4318)
							(mid 0.402042 0.402042)
							(end 0.4318 0.3302)
						)
						(arc
							(start 0.4318 -0.3302)
							(mid 0.402042 -0.402042)
							(end 0.3302 -0.4318)
						)
					)
					(width 0)
					(fill yes)
				)
			)
		)
	)
	(footprint ""
		(layer "F.Cu")
		(at 166.649146 -146.302222 180)
		(property "Reference" "C4A13"
			(at 0 0 180)
			(layer "F.SilkS")
			(hide yes)
			(effects
				(font
					(size 1.27 1.27)
				)
			)
		)
		(property "Value" ""
			(at 0 0 180)
			(layer "F.Fab")
			(effects
				(font
					(size 1.27 1.27)
				)
			)
		)
		(duplicate_pad_numbers_are_jumpers no)
		(fp_rect
			(start -0.7239 1.9939)
			(end 0.7239 -0.2159)
			(stroke
				(width 0)
				(type default)
			)
			(fill no)
			(layer "F.CrtYd")
		)
		(fp_line
			(start 0.7239 1.9939)
			(end 0.7239 -0.2159)
			(stroke
				(width 0.1)
				(type default)
			)
			(layer "F.Fab")
		)
		(fp_line
			(start 0.7239 -0.2159)
			(end -0.7239 -0.2159)
			(stroke
				(width 0.1)
				(type default)
			)
			(layer "F.Fab")
		)
		(fp_line
			(start -0.7239 1.9939)
			(end 0.7239 1.9939)
			(stroke
				(width 0.1)
				(type default)
			)
			(layer "F.Fab")
		)
		(fp_line
			(start -0.7239 -0.2159)
			(end -0.7239 1.9939)
			(stroke
				(width 0.1)
				(type default)
			)
			(layer "F.Fab")
		)
		(pad "1" smd rect
			(at 0 0 180)
			(size 1.27 1.016)
			(layers "F.Cu" "F.Mask" "F.Paste")
			(net "PVTT_KLM")
		)
		(pad "2" smd rect
			(at 0 1.778 180)
			(size 1.27 1.016)
			(layers "F.Cu" "F.Mask" "F.Paste")
			(net "GND")
		)
		(zone
			(layer "F.Cu")
			(hatch none 0.5)
			(connect_pads
				(clearance 0)
			)
			(min_thickness 0.25)
			(keepout
				(tracks not_allowed)
				(vias allowed)
				(pads allowed)
				(copperpour not_allowed)
				(footprints allowed)
			)
			(placement
				(enabled no)
				(sheetname "")
			)
			(fill
				(thermal_gap 0.5)
				(thermal_bridge_width 0.5)
				(island_removal_mode 0)
			)
			(polygon
				(pts
					(xy 167.284146 -147.572222) (xy 166.014146 -147.572222) (xy 166.014146 -146.810222) (xy 167.284146 -146.810222)
				)
			)
		)
	)
	(footprint ""
		(layer "F.Cu")
		(at 13.8938 -33.909 90)
		(property "Reference" "C1F5"
			(at 0 0 90)
			(layer "F.SilkS")
			(hide yes)
			(effects
				(font
					(size 1.27 1.27)
				)
			)
		)
		(property "Value" ""
			(at 0 0 90)
			(layer "F.Fab")
			(effects
				(font
					(size 1.27 1.27)
				)
			)
		)
		(duplicate_pad_numbers_are_jumpers no)
		(fp_rect
			(start -0.3048 -0.1016)
			(end 0.3048 0.9906)
			(stroke
				(width 0)
				(type default)
			)
			(fill no)
			(layer "F.CrtYd")
		)
		(fp_line
			(start 0.3048 -0.1016)
			(end -0.3048 -0.1016)
			(stroke
				(width 0.1)
				(type default)
			)
			(layer "F.Fab")
		)
		(fp_line
			(start -0.3048 -0.1016)
			(end -0.3048 0.9906)
			(stroke
				(width 0.1)
				(type default)
			)
			(layer "F.Fab")
		)
		(fp_line
			(start 0.3048 0.9906)
			(end 0.3048 -0.1016)
			(stroke
				(width 0.1)
				(type default)
			)
			(layer "F.Fab")
		)
		(fp_line
			(start -0.3048 0.9906)
			(end 0.3048 0.9906)
			(stroke
				(width 0.1)
				(type default)
			)
			(layer "F.Fab")
		)
		(pad "1" smd rect
			(at 0 0 90)
			(size 0.508 0.508)
			(layers "F.Cu" "F.Mask" "F.Paste")
			(net "P3E_CPU1_PE3_MP_C_TXP<6>")
		)
		(pad "2" smd rect
			(at 0 0.889 90)
			(size 0.508 0.508)
			(layers "F.Cu" "F.Mask" "F.Paste")
			(net "P3E_CPU1_PE3_MP_TXP<6>")
		)
		(zone
			(layer "F.Cu")
			(hatch none 0.5)
			(connect_pads
				(clearance 0)
			)
			(min_thickness 0.25)
			(keepout
				(tracks not_allowed)
				(vias allowed)
				(pads allowed)
				(copperpour not_allowed)
				(footprints allowed)
			)
			(placement
				(enabled no)
				(sheetname "")
			)
			(fill
				(thermal_gap 0.5)
				(thermal_bridge_width 0.5)
				(island_removal_mode 0)
			)
			(polygon
				(pts
					(xy 14.1478 -33.655) (xy 14.5288 -33.655) (xy 14.5288 -34.163) (xy 14.1478 -34.163)
				)
			)
		)
		(zone
			(layer "F.Cu")
			(hatch none 0.5)
			(connect_pads
				(clearance 0)
			)
			(min_thickness 0.25)
			(keepout
				(tracks allowed)
				(vias not_allowed)
				(pads allowed)
				(copperpour not_allowed)
				(footprints allowed)
			)
			(placement
				(enabled no)
				(sheetname "")
			)
			(fill
				(thermal_gap 0.5)
				(thermal_bridge_width 0.5)
				(island_removal_mode 0)
			)
			(polygon
				(pts
					(xy 14.1478 -33.655) (xy 14.5288 -33.655) (xy 14.5288 -34.163) (xy 14.1478 -34.163)
				)
			)
		)
	)
)
